(kicad_pcb
	(version 20260206)
	(generator "pcbnew")
	(generator_version "10.0")
	(general
		(thickness 1.6)
		(legacy_teardrops no)
	)
	(paper "A4")
	(title_block
		(title "Bryce Canyon_F.DPB_16315-1-OCP.brd")
		(comment 1 "Bryce Canyon / footprints 749-755 of 2223")
	)
	(layers
		(0 "F.Cu" signal "TOP")
		(4 "In1.Cu" signal "L2GND")
		(6 "In2.Cu" signal "L3")
		(8 "In3.Cu" signal "L4GND")
		(10 "In4.Cu" signal "L5")
		(12 "In5.Cu" signal "L6VCC")
		(14 "In6.Cu" signal "L7VCC")
		(16 "In7.Cu" signal "L8")
		(18 "In8.Cu" signal "L9GND")
		(20 "In9.Cu" signal "L10")
		(22 "In10.Cu" signal "L11GND")
		(2 "B.Cu" signal "BOTTOM")
		(9 "F.Adhes" user "F.Adhesive")
		(11 "B.Adhes" user "B.Adhesive")
		(13 "F.Paste" user "Package Geometry/Pastemask Top")
		(15 "B.Paste" user "Package Geometry/Pastemask Bottom")
		(5 "F.SilkS" user "Ref Des/Silkscreen Top")
		(7 "B.SilkS" user "Ref Des/Silkscreen Bottom")
		(1 "F.Mask" user "Board Geometry/Soldermask Top")
		(3 "B.Mask" user "Board Geometry/Soldermask Bottom")
		(17 "Dwgs.User" user "User.Drawings")
		(19 "Cmts.User" user "User.Comments")
		(21 "Eco1.User" user "User.Eco1")
		(23 "Eco2.User" user "User.Eco2")
		(25 "Edge.Cuts" user "Board Geometry/Outline")
		(27 "Margin" user)
		(31 "F.CrtYd" user "Package Geometry/Place Bound Top")
		(29 "B.CrtYd" user "Package Geometry/Place Bound Bottom")
		(35 "F.Fab" user "Ref Des/Assembly Top")
		(33 "B.Fab" user "Ref Des/Assembly Bottom")
	)
	(footprint ""
		(layer "F.Cu")
		(at 51.980846 -48.554894 180)
		(property "Reference" "Q151"
			(at 0 0 180)
			(layer "F.SilkS")
			(hide yes)
			(effects
				(font
					(size 1.27 1.27)
				)
			)
		)
		(property "Value" "2N7002KDW-GP"
			(at -2.3622 -8.2042 180)
			(unlocked yes)
			(layer "F.Fab")
			(hide yes)
			(effects
				(font
					(size 1.016 1.016)
					(thickness 0.1524)
				)
			)
		)
		(property "Device Type" "SOT-363H44"
			(at -2.3622 -10.1092 180)
			(unlocked yes)
			(layer "F.Fab")
			(hide yes)
			(effects
				(font
					(size 1.016 1.016)
					(thickness 0.1524)
				)
			)
		)
		(duplicate_pad_numbers_are_jumpers no)
		(fp_line
			(start 1.4478 1.7018)
			(end 1.4478 -1.7018)
			(stroke
				(width 0.1524)
				(type default)
			)
			(layer "F.SilkS")
		)
		(fp_line
			(start 1.4478 -1.7018)
			(end -1.4478 -1.7018)
			(stroke
				(width 0.1524)
				(type default)
			)
			(layer "F.SilkS")
		)
		(fp_line
			(start -1.27 1.524)
			(end -1.27 0.6604)
			(stroke
				(width 0.4826)
				(type default)
			)
			(layer "F.SilkS")
		)
		(fp_line
			(start -1.4478 1.7018)
			(end 1.4478 1.7018)
			(stroke
				(width 0.1524)
				(type default)
			)
			(layer "F.SilkS")
		)
		(fp_line
			(start -1.4478 -1.7018)
			(end -1.4478 1.7018)
			(stroke
				(width 0.1524)
				(type default)
			)
			(layer "F.SilkS")
		)
		(fp_poly
			(pts
				(xy -1.524 -1.778) (xy 1.524 -1.778) (xy 1.524 1.778) (xy -1.524 1.778)
			)
			(stroke
				(width 0)
				(type default)
			)
			(fill no)
			(layer "F.CrtYd")
		)
		(fp_poly
			(pts
				(xy -1.524 -1.778) (xy 1.524 -1.778) (xy 1.524 1.778) (xy -1.524 1.778)
			)
			(stroke
				(width 0)
				(type default)
			)
			(fill no)
			(layer "F.Fab")
		)
		(pad "1" smd rect
			(at -0.65024 0.9398 180)
			(size 0.4064 1.016)
			(layers "F.Cu" "F.Mask" "F.Paste")
			(net "GND")
		)
		(pad "2" smd rect
			(at 0 0.9398 180)
			(size 0.4064 1.016)
			(layers "F.Cu" "F.Mask" "F.Paste")
			(net "SW_PWR_R_HDD25")
		)
		(pad "3" smd rect
			(at 0.65024 0.9398 180)
			(size 0.4064 1.016)
			(layers "F.Cu" "F.Mask" "F.Paste")
			(net "SW_HDD_P25")
		)
		(pad "4" smd rect
			(at 0.65024 -0.9398 180)
			(size 0.4064 1.016)
			(layers "F.Cu" "F.Mask" "F.Paste")
			(net "GND")
		)
		(pad "5" smd rect
			(at 0 -0.9398 180)
			(size 0.4064 1.016)
			(layers "F.Cu" "F.Mask" "F.Paste")
			(net "SW_HDD_G25")
		)
		(pad "6" smd rect
			(at -0.65024 -0.9398 180)
			(size 0.4064 1.016)
			(layers "F.Cu" "F.Mask" "F.Paste")
			(net "SW_HDD_R25")
		)
	)
	(footprint ""
		(layer "F.Cu")
		(at 156.275532 -137.85723 90)
		(property "Reference" "R1052"
			(at 0 0 90)
			(layer "F.SilkS")
			(hide yes)
			(effects
				(font
					(size 1.27 1.27)
				)
			)
		)
		(property "Value" "10R2F-L-GP"
			(at 0.064008 -3.993896 90)
			(unlocked yes)
			(layer "F.Fab")
			(hide yes)
			(effects
				(font
					(size 1.016 1.016)
					(thickness 0.1524)
				)
			)
		)
		(property "Device Type" "R402H14"
			(at 0.064008 -5.517896 90)
			(unlocked yes)
			(layer "F.Fab")
			(hide yes)
			(effects
				(font
					(size 1.016 1.016)
					(thickness 0.1524)
				)
			)
		)
		(duplicate_pad_numbers_are_jumpers no)
		(fp_line
			(start 0.508 -0.9398)
			(end -0.508 -0.9398)
			(stroke
				(width 0.1524)
				(type default)
			)
			(layer "F.SilkS")
		)
		(fp_line
			(start -0.508 -0.9398)
			(end -0.508 0.9398)
			(stroke
				(width 0.1524)
				(type default)
			)
			(layer "F.SilkS")
		)
		(fp_rect
			(start -0.508 0.9398)
			(end 0.508 -0.9398)
			(stroke
				(width 0)
				(type default)
			)
			(fill no)
			(layer "F.CrtYd")
		)
		(fp_rect
			(start -0.508 0.9398)
			(end 0.508 -0.9398)
			(stroke
				(width 0)
				(type default)
			)
			(fill no)
			(layer "F.Fab")
		)
		(pad "1" smd custom
			(at 0 -0.4445 90)
			(size 0.1397 0.1397)
			(layers "F.Cu" "F.Mask" "F.Paste")
			(net "MB0_CM_SENSE_R1_P")
			(options
				(clearance outline)
				(anchor circle)
			)
			(primitives
				(gr_poly
					(pts
						(arc
							(start -0.1778 -0.2794)
							(mid -0.249642 -0.249642)
							(end -0.2794 -0.1778)
						)
						(arc
							(start -0.2794 0.1778)
							(mid -0.249642 0.249642)
							(end -0.1778 0.2794)
						)
						(arc
							(start 0.1778 0.2794)
							(mid 0.249642 0.249642)
							(end 0.2794 0.1778)
						)
						(arc
							(start 0.2794 -0.1778)
							(mid 0.249642 -0.249642)
							(end 0.1778 -0.2794)
						)
					)
					(width 0)
					(fill yes)
				)
			)
		)
		(pad "2" smd custom
			(at 0 0.4445 90)
			(size 0.1397 0.1397)
			(layers "F.Cu" "F.Mask" "F.Paste")
			(net "MB0_CM_SENSE_P")
			(options
				(clearance outline)
				(anchor circle)
			)
			(primitives
				(gr_poly
					(pts
						(arc
							(start -0.1778 -0.2794)
							(mid -0.249642 -0.249642)
							(end -0.2794 -0.1778)
						)
						(arc
							(start -0.2794 0.1778)
							(mid -0.249642 0.249642)
							(end -0.1778 0.2794)
						)
						(arc
							(start 0.1778 0.2794)
							(mid 0.249642 0.249642)
							(end 0.2794 0.1778)
						)
						(arc
							(start 0.2794 -0.1778)
							(mid 0.249642 -0.249642)
							(end 0.1778 -0.2794)
						)
					)
					(width 0)
					(fill yes)
				)
			)
		)
	)
	(footprint ""
		(layer "F.Cu")
		(at 282.067 -272.3134)
		(property "Reference" "R122"
			(at 0 0 0)
			(layer "F.SilkS")
			(hide yes)
			(effects
				(font
					(size 1.27 1.27)
				)
			)
		)
		(property "Value" "4K7R2F-GP"
			(at 0.064008 -3.993896 0)
			(unlocked yes)
			(layer "F.Fab")
			(hide yes)
			(effects
				(font
					(size 1.016 1.016)
					(thickness 0.1524)
				)
			)
		)
		(property "Device Type" "R402H16"
			(at 0.064008 -5.517896 0)
			(unlocked yes)
			(layer "F.Fab")
			(hide yes)
			(effects
				(font
					(size 1.016 1.016)
					(thickness 0.1524)
				)
			)
		)
		(duplicate_pad_numbers_are_jumpers no)
		(fp_line
			(start -0.508 -0.9398)
			(end -0.508 0.9398)
			(stroke
				(width 0.1524)
				(type default)
			)
			(layer "F.SilkS")
		)
		(fp_line
			(start 0.508 -0.9398)
			(end -0.508 -0.9398)
			(stroke
				(width 0.1524)
				(type default)
			)
			(layer "F.SilkS")
		)
		(fp_rect
			(start -0.508 0.9398)
			(end 0.508 -0.9398)
			(stroke
				(width 0)
				(type default)
			)
			(fill no)
			(layer "F.CrtYd")
		)
		(fp_rect
			(start -0.508 0.9398)
			(end 0.508 -0.9398)
			(stroke
				(width 0)
				(type default)
			)
			(fill no)
			(layer "F.Fab")
		)
		(pad "1" smd custom
			(at 0 -0.4445)
			(size 0.1397 0.1397)
			(layers "F.Cu" "F.Mask" "F.Paste")
			(net "IO_EXP2_HDD_FAULT_INT_N")
			(options
				(clearance outline)
				(anchor circle)
			)
			(primitives
				(gr_poly
					(pts
						(arc
							(start -0.1778 -0.2794)
							(mid -0.249642 -0.249642)
							(end -0.2794 -0.1778)
						)
						(arc
							(start -0.2794 0.1778)
							(mid -0.249642 0.249642)
							(end -0.1778 0.2794)
						)
						(arc
							(start 0.1778 0.2794)
							(mid 0.249642 0.249642)
							(end 0.2794 0.1778)
						)
						(arc
							(start 0.2794 -0.1778)
							(mid 0.249642 -0.249642)
							(end 0.1778 -0.2794)
						)
					)
					(width 0)
					(fill yes)
				)
			)
		)
		(pad "2" smd custom
			(at 0 0.4445)
			(size 0.1397 0.1397)
			(layers "F.Cu" "F.Mask" "F.Paste")
			(net "P3V3_STBY_A")
			(options
				(clearance outline)
				(anchor circle)
			)
			(primitives
				(gr_poly
					(pts
						(arc
							(start -0.1778 -0.2794)
							(mid -0.249642 -0.249642)
							(end -0.2794 -0.1778)
						)
						(arc
							(start -0.2794 0.1778)
							(mid -0.249642 0.249642)
							(end -0.1778 0.2794)
						)
						(arc
							(start 0.1778 0.2794)
							(mid 0.249642 0.249642)
							(end 0.2794 0.1778)
						)
						(arc
							(start 0.2794 -0.1778)
							(mid 0.249642 -0.249642)
							(end 0.1778 -0.2794)
						)
					)
					(width 0)
					(fill yes)
				)
			)
		)
	)
	(footprint ""
		(layer "F.Cu")
		(at 414.639252 -158.939992 90)
		(property "Reference" "VIA10"
			(at 0 0 90)
			(layer "F.SilkS")
			(hide yes)
			(effects
				(font
					(size 1.27 1.27)
				)
			)
		)
		(property "Value" "100OHM-8L-1D6MM-L18L16-GP"
			(at -3.7211 -4.5085 90)
			(unlocked yes)
			(layer "F.Fab")
			(hide yes)
			(effects
				(font
					(size 1.016 1.016)
					(thickness 0.1524)
				)
			)
		)
		(property "Device Type" "VIA-PCIE-4P-394076"
			(at -3.7211 -6.0325 90)
			(unlocked yes)
			(layer "F.Fab")
			(hide yes)
			(effects
				(font
					(size 1.016 1.016)
					(thickness 0.1524)
				)
			)
		)
		(duplicate_pad_numbers_are_jumpers no)
		(fp_rect
			(start -1.9685 0.381)
			(end 1.9685 -0.381)
			(stroke
				(width 0)
				(type default)
			)
			(fill no)
			(layer "F.CrtYd")
		)
		(fp_rect
			(start -1.9685 0.381)
			(end 1.9685 -0.381)
			(stroke
				(width 0)
				(type default)
			)
			(fill no)
			(layer "F.Fab")
		)
		(pad "1" thru_hole circle
			(at -1.5875 0 90)
			(size 0.508 0.508)
			(drill 0.254)
			(layers "*.Cu" "*.Mask")
			(remove_unused_layers no)
			(net "GND")
			(clearance 0.127)
			(thermal_gap 0.127)
		)
		(pad "2" thru_hole circle
			(at -0.5715 0 90)
			(size 0.508 0.508)
			(drill 0.254)
			(layers "*.Cu" "*.Mask")
			(remove_unused_layers no)
			(net "PHY_SCC_A_TO_DRV_A_21_DP")
			(clearance 0.127)
			(thermal_gap 0.127)
		)
		(pad "3" thru_hole circle
			(at 0.5715 0 90)
			(size 0.508 0.508)
			(drill 0.254)
			(layers "*.Cu" "*.Mask")
			(remove_unused_layers no)
			(net "PHY_SCC_A_TO_DRV_A_21_DN")
			(clearance 0.127)
			(thermal_gap 0.127)
		)
		(pad "4" thru_hole circle
			(at 1.5875 0 90)
			(size 0.508 0.508)
			(drill 0.254)
			(layers "*.Cu" "*.Mask")
			(remove_unused_layers no)
			(net "GND")
			(clearance 0.127)
			(thermal_gap 0.127)
		)
	)
	(footprint ""
		(layer "F.Cu")
		(at 377.2154 -133.5786 90)
		(property "Reference" "R1075"
			(at 0 0 90)
			(layer "F.SilkS")
			(hide yes)
			(effects
				(font
					(size 1.27 1.27)
				)
			)
		)
		(property "Value" "0R2J-2-GP"
			(at 0.064008 -3.993896 90)
			(unlocked yes)
			(layer "F.Fab")
			(hide yes)
			(effects
				(font
					(size 1.016 1.016)
					(thickness 0.1524)
				)
			)
		)
		(property "Device Type" "R402H16"
			(at 0.064008 -5.517896 90)
			(unlocked yes)
			(layer "F.Fab")
			(hide yes)
			(effects
				(font
					(size 1.016 1.016)
					(thickness 0.1524)
				)
			)
		)
		(duplicate_pad_numbers_are_jumpers no)
		(fp_line
			(start 0.508 -0.9398)
			(end -0.508 -0.9398)
			(stroke
				(width 0.1524)
				(type default)
			)
			(layer "F.SilkS")
		)
		(fp_line
			(start -0.508 -0.9398)
			(end -0.508 0.9398)
			(stroke
				(width 0.1524)
				(type default)
			)
			(layer "F.SilkS")
		)
		(fp_rect
			(start -0.508 0.9398)
			(end 0.508 -0.9398)
			(stroke
				(width 0)
				(type default)
			)
			(fill no)
			(layer "F.CrtYd")
		)
		(fp_rect
			(start -0.508 0.9398)
			(end 0.508 -0.9398)
			(stroke
				(width 0)
				(type default)
			)
			(fill no)
			(layer "F.Fab")
		)
		(pad "1" smd custom
			(at 0 -0.4445 90)
			(size 0.1397 0.1397)
			(layers "F.Cu" "F.Mask" "F.Paste")
			(net "MB1_CM_ADR2_R")
			(options
				(clearance outline)
				(anchor circle)
			)
			(primitives
				(gr_poly
					(pts
						(arc
							(start -0.1778 -0.2794)
							(mid -0.249642 -0.249642)
							(end -0.2794 -0.1778)
						)
						(arc
							(start -0.2794 0.1778)
							(mid -0.249642 0.249642)
							(end -0.1778 0.2794)
						)
						(arc
							(start 0.1778 0.2794)
							(mid 0.249642 0.249642)
							(end 0.2794 0.1778)
						)
						(arc
							(start 0.2794 -0.1778)
							(mid 0.249642 -0.249642)
							(end 0.1778 -0.2794)
						)
					)
					(width 0)
					(fill yes)
				)
			)
		)
		(pad "2" smd custom
			(at 0 0.4445 90)
			(size 0.1397 0.1397)
			(layers "F.Cu" "F.Mask" "F.Paste")
			(net "AGND_CURRENT_MONOB")
			(options
				(clearance outline)
				(anchor circle)
			)
			(primitives
				(gr_poly
					(pts
						(arc
							(start -0.1778 -0.2794)
							(mid -0.249642 -0.249642)
							(end -0.2794 -0.1778)
						)
						(arc
							(start -0.2794 0.1778)
							(mid -0.249642 0.249642)
							(end -0.1778 0.2794)
						)
						(arc
							(start 0.1778 0.2794)
							(mid 0.249642 0.249642)
							(end 0.2794 0.1778)
						)
						(arc
							(start 0.2794 -0.1778)
							(mid 0.249642 -0.249642)
							(end 0.1778 -0.2794)
						)
					)
					(width 0)
					(fill yes)
				)
			)
		)
	)
	(footprint ""
		(layer "F.Cu")
		(at 440.694826 -242.25377)
		(property "Reference" "R265"
			(at 0 0 0)
			(layer "F.SilkS")
			(hide yes)
			(effects
				(font
					(size 1.27 1.27)
				)
			)
		)
		(property "Value" "130R3F-GP"
			(at -0.0254 -2.5146 0)
			(unlocked yes)
			(layer "F.Fab")
			(hide yes)
			(effects
				(font
					(size 1.016 1.016)
					(thickness 0.1524)
				)
			)
		)
		(property "Device Type" "R603H22"
			(at -0.0254 -4.0386 0)
			(unlocked yes)
			(layer "F.Fab")
			(hide yes)
			(effects
				(font
					(size 1.016 1.016)
					(thickness 0.1524)
				)
			)
		)
		(duplicate_pad_numbers_are_jumpers no)
		(fp_line
			(start -0.4826 0)
			(end -0.2032 0)
			(stroke
				(width 0.2032)
				(type default)
			)
			(layer "F.SilkS")
		)
		(fp_line
			(start 0.2032 0)
			(end 0.4826 0)
			(stroke
				(width 0.2032)
				(type default)
			)
			(layer "F.SilkS")
		)
		(fp_rect
			(start -0.5842 1.3335)
			(end 0.5842 -1.3335)
			(stroke
				(width 0)
				(type default)
			)
			(fill no)
			(layer "F.CrtYd")
		)
		(fp_rect
			(start -0.5842 1.3335)
			(end 0.5842 -1.3335)
			(stroke
				(width 0)
				(type default)
			)
			(fill no)
			(layer "F.Fab")
		)
		(pad "1" smd custom
			(at 0 -0.762)
			(size 0.2159 0.2159)
			(layers "F.Cu" "F.Mask" "F.Paste")
			(net "P5V_A_3")
			(options
				(clearance outline)
				(anchor circle)
			)
			(primitives
				(gr_poly
					(pts
						(arc
							(start -0.3302 -0.4318)
							(mid -0.402042 -0.402042)
							(end -0.4318 -0.3302)
						)
						(arc
							(start -0.4318 0.3302)
							(mid -0.402042 0.402042)
							(end -0.3302 0.4318)
						)
						(arc
							(start 0.3302 0.4318)
							(mid 0.402042 0.402042)
							(end 0.4318 0.3302)
						)
						(arc
							(start 0.4318 -0.3302)
							(mid 0.402042 -0.402042)
							(end 0.3302 -0.4318)
						)
					)
					(width 0)
					(fill yes)
				)
			)
		)
		(pad "2" smd custom
			(at 0 0.762)
			(size 0.2159 0.2159)
			(layers "F.Cu" "F.Mask" "F.Paste")
			(net "FLT_HDD10")
			(options
				(clearance outline)
				(anchor circle)
			)
			(primitives
				(gr_poly
					(pts
						(arc
							(start -0.3302 -0.4318)
							(mid -0.402042 -0.402042)
							(end -0.4318 -0.3302)
						)
						(arc
							(start -0.4318 0.3302)
							(mid -0.402042 0.402042)
							(end -0.3302 0.4318)
						)
						(arc
							(start 0.3302 0.4318)
							(mid 0.402042 0.402042)
							(end 0.4318 0.3302)
						)
						(arc
							(start 0.4318 -0.3302)
							(mid 0.402042 -0.402042)
							(end 0.3302 -0.4318)
						)
					)
					(width 0)
					(fill yes)
				)
			)
		)
	)
	(footprint ""
		(layer "F.Cu")
		(at 80.900016 -209.399886)
		(property "Reference" "FLED3"
			(at 0 0 0)
			(layer "F.SilkS")
			(hide yes)
			(effects
				(font
					(size 1.27 1.27)
				)
			)
		)
		(property "Value" "LED-BY-19-GP"
			(at -2.132076 1.414018 0)
			(unlocked yes)
			(layer "F.Fab")
			(hide yes)
			(effects
				(font
					(size 1.016 1.016)
					(thickness 0.1524)
				)
			)
		)
		(property "Device Type" "LED-1615-4PH26"
			(at -2.132076 -0.109982 0)
			(unlocked yes)
			(layer "F.Fab")
			(hide yes)
			(effects
				(font
					(size 1.016 1.016)
					(thickness 0.1524)
				)
			)
		)
		(duplicate_pad_numbers_are_jumpers no)
		(fp_line
			(start -1.2954 0.254)
			(end -1.2954 1.6002)
			(stroke
				(width 0.508)
				(type default)
			)
			(layer "F.SilkS")
		)
		(fp_line
			(start -1.2954 1.6002)
			(end 1.2954 1.6002)
			(stroke
				(width 0.508)
				(type default)
			)
			(layer "F.SilkS")
		)
		(fp_line
			(start -1.1176 -1.4224)
			(end 1.1176 -1.4224)
			(stroke
				(width 0.1524)
				(type default)
			)
			(layer "F.SilkS")
		)
		(fp_line
			(start -1.1176 1.4224)
			(end -1.1176 -1.4224)
			(stroke
				(width 0.1524)
				(type default)
			)
			(layer "F.SilkS")
		)
		(fp_line
			(start 1.1176 -1.4224)
			(end 1.1176 1.4224)
			(stroke
				(width 0.1524)
				(type default)
			)
			(layer "F.SilkS")
		)
		(fp_line
			(start 1.1176 1.4224)
			(end -1.1176 1.4224)
			(stroke
				(width 0.1524)
				(type default)
			)
			(layer "F.SilkS")
		)
		(fp_line
			(start 1.2954 1.6002)
			(end 1.2954 0.254)
			(stroke
				(width 0.508)
				(type default)
			)
			(layer "F.SilkS")
		)
		(fp_rect
			(start -0.7493 0.8001)
			(end 0.7493 -0.8001)
			(stroke
				(width 0)
				(type default)
			)
			(fill no)
			(layer "F.CrtYd")
		)
		(fp_poly
			(pts
				(xy -1.3716 1.6764) (xy -1.3716 -1.6764) (xy 1.3716 -1.6764) (xy 1.3716 0.0635) (xy 0.7493 0.0635)
				(xy 0.7493 -0.8001) (xy -0.7493 -0.8001) (xy -0.7493 0.8001) (xy 0.7493 0.8001) (xy 0.7493 0.0762)
				(xy 1.3716 0.0762) (xy 1.3716 1.6764)
			)
			(stroke
				(width 0)
				(type default)
			)
			(fill no)
			(layer "F.CrtYd")
		)
		(fp_rect
			(start -1.3716 1.6764)
			(end 1.3716 -1.6764)
			(stroke
				(width 0)
				(type default)
			)
			(fill no)
			(layer "F.Fab")
		)
		(pad "1" smd rect
			(at 0.50038 -0.73025)
			(size 0.7112 0.8636)
			(layers "F.Cu" "F.Mask" "F.Paste")
			(net "DRV_ACT_2")
		)
		(pad "2" smd rect
			(at -0.50038 -0.73025)
			(size 0.7112 0.8636)
			(layers "F.Cu" "F.Mask" "F.Paste")
			(net "FLT_HDD2")
		)
		(pad "3" smd rect
			(at 0.50038 0.73025)
			(size 0.7112 0.8636)
			(layers "F.Cu" "F.Mask" "F.Paste")
			(net "DRV_ACT_2_N")
		)
		(pad "4" smd rect
			(at -0.50038 0.73025)
			(size 0.7112 0.8636)
			(layers "F.Cu" "F.Mask" "F.Paste")
			(net "FLT_HDD2_N")
		)
	)
)
